# SCM (Grand Teton) — schematic netlist excerpt (pin names and nets, part order shuffled) for the footprints in the layout excerpt that follows; sources: Cadence DE-HDL packaged netlist, KiCad conversion of 12092022_DA0F0TMDCD0_F0T_Management_Board_D_brd_V3_OCP.brd

PC268  Q_CAP  22UF 4V 20% X6S  pkg 0805  page 56 : A = P1V0_AUX ; B = GND
R243  Q_RES  33.2 1% CHIP  pkg 0402LF  page 10 : A = PWRGD_PSU_AC_PWROK ; B = PWRGD_PSU_AC_PWROK_R

(kicad_pcb
	(version 20260206)
	(generator "pcbnew")
	(generator_version "10.0")
	(general
		(thickness 1.6)
		(legacy_teardrops no)
	)
	(paper "A4")
	(title_block
		(title "12092022_DA0F0TMDCD0_F0T_Management_Board_D_brd_V3_OCP.brd")
		(comment 1 "Grand Teton / footprints 859-860 of 1440")
	)
	(layers
		(0 "F.Cu" signal "TOP")
		(4 "In1.Cu" signal "GND")
		(6 "In2.Cu" signal "IN1")
		(8 "In3.Cu" signal "GND1")
		(10 "In4.Cu" signal "IN2")
		(12 "In5.Cu" signal "VCC")
		(14 "In6.Cu" signal "VCC1")
		(16 "In7.Cu" signal "IN3")
		(18 "In8.Cu" signal "GND2")
		(20 "In9.Cu" signal "IN4")
		(22 "In10.Cu" signal "GND3")
		(2 "B.Cu" signal "BOTTOM")
		(9 "F.Adhes" user "F.Adhesive")
		(11 "B.Adhes" user "B.Adhesive")
		(13 "F.Paste" user "Package Geometry/Pastemask Top")
		(15 "B.Paste" user "Package Geometry/Pastemask Bottom")
		(5 "F.SilkS" user "Ref Des/Silkscreen Top")
		(7 "B.SilkS" user "Ref Des/Silkscreen Bottom")
		(1 "F.Mask" user "Board Geometry/Soldermask Top")
		(3 "B.Mask" user "Board Geometry/Soldermask Bottom")
		(17 "Dwgs.User" user "User.Drawings")
		(19 "Cmts.User" user "User.Comments")
		(21 "Eco1.User" user "User.Eco1")
		(23 "Eco2.User" user "User.Eco2")
		(25 "Edge.Cuts" user "Board Geometry/Outline")
		(27 "Margin" user)
		(31 "F.CrtYd" user "Package Geometry/Place Bound Top")
		(29 "B.CrtYd" user "Package Geometry/Place Bound Bottom")
		(35 "F.Fab" user "Ref Des/Assembly Top")
		(33 "B.Fab" user "Ref Des/Assembly Bottom")
	)
	(footprint ""
		(layer "B.Cu")
		(at 32.639 -106.553 -90)
		(property "Reference" "R243"
			(at 0 0 90)
			(layer "B.SilkS")
			(hide yes)
			(effects
				(font
					(size 1.27 1.27)
				)
				(justify mirror)
			)
		)
		(property "Value" ""
			(at 0 0 90)
			(layer "B.Fab")
			(effects
				(font
					(size 1.27 1.27)
				)
				(justify mirror)
			)
		)
		(duplicate_pad_numbers_are_jumpers no)
		(fp_line
			(start -0.7874 0.4064)
			(end 0.7874 0.4064)
			(stroke
				(width 0.1524)
				(type default)
			)
			(layer "B.SilkS")
		)
		(fp_line
			(start 0.7874 0.4064)
			(end 0.7874 -0.4064)
			(stroke
				(width 0.1524)
				(type default)
			)
			(layer "B.SilkS")
		)
		(fp_line
			(start -0.7874 -0.4064)
			(end -0.7874 0.4064)
			(stroke
				(width 0.1524)
				(type default)
			)
			(layer "B.SilkS")
		)
		(fp_line
			(start 0.7874 -0.4064)
			(end -0.7874 -0.4064)
			(stroke
				(width 0.1524)
				(type default)
			)
			(layer "B.SilkS")
		)
		(fp_line
			(start -0.67945 0.3048)
			(end -0.120396 0.3048)
			(stroke
				(width 0.1)
				(type default)
			)
			(layer "B.Fab")
		)
		(fp_line
			(start -0.120396 0.3048)
			(end -0.120396 0.2794)
			(stroke
				(width 0.1)
				(type default)
			)
			(layer "B.Fab")
		)
		(fp_line
			(start 0.12065 0.3048)
			(end 0.67945 0.3048)
			(stroke
				(width 0.1)
				(type default)
			)
			(layer "B.Fab")
		)
		(fp_line
			(start 0.67945 0.3048)
			(end 0.67945 -0.305054)
			(stroke
				(width 0.1)
				(type default)
			)
			(layer "B.Fab")
		)
		(fp_line
			(start -0.120396 0.2794)
			(end 0.12065 0.2794)
			(stroke
				(width 0.1)
				(type default)
			)
			(layer "B.Fab")
		)
		(fp_line
			(start 0.12065 0.2794)
			(end 0.12065 0.3048)
			(stroke
				(width 0.1)
				(type default)
			)
			(layer "B.Fab")
		)
		(fp_line
			(start -0.12065 -0.2794)
			(end -0.12065 -0.3048)
			(stroke
				(width 0.1)
				(type default)
			)
			(layer "B.Fab")
		)
		(fp_line
			(start 0.12065 -0.2794)
			(end -0.12065 -0.2794)
			(stroke
				(width 0.1)
				(type default)
			)
			(layer "B.Fab")
		)
		(fp_line
			(start -0.67945 -0.3048)
			(end -0.67945 0.3048)
			(stroke
				(width 0.1)
				(type default)
			)
			(layer "B.Fab")
		)
		(fp_line
			(start -0.12065 -0.3048)
			(end -0.67945 -0.3048)
			(stroke
				(width 0.1)
				(type default)
			)
			(layer "B.Fab")
		)
		(fp_line
			(start 0.12065 -0.305054)
			(end 0.12065 -0.2794)
			(stroke
				(width 0.1)
				(type default)
			)
			(layer "B.Fab")
		)
		(fp_line
			(start 0.67945 -0.305054)
			(end 0.12065 -0.305054)
			(stroke
				(width 0.1)
				(type default)
			)
			(layer "B.Fab")
		)
		(pad "1" smd circle
			(at 0.40005 0 90)
			(size 0 0)
			(layers "B.Cu" "B.Mask" "B.Paste")
			(net "PWRGD_PSU_AC_PWROK")
		)
		(pad "2" smd circle
			(at -0.40005 0 90)
			(size 0 0)
			(layers "B.Cu" "B.Mask" "B.Paste")
			(net "PWRGD_PSU_AC_PWROK_R")
		)
	)
	(footprint ""
		(layer "B.Cu")
		(at 17.907 -24.003 -90)
		(property "Reference" "PC268"
			(at 0 0 90)
			(layer "B.SilkS")
			(hide yes)
			(effects
				(font
					(size 1.27 1.27)
				)
				(justify mirror)
			)
		)
		(property "Value" ""
			(at 0 0 90)
			(layer "B.Fab")
			(effects
				(font
					(size 1.27 1.27)
				)
				(justify mirror)
			)
		)
		(duplicate_pad_numbers_are_jumpers no)
		(fp_line
			(start -1.651 0.8382)
			(end 1.651 0.8382)
			(stroke
				(width 0.1524)
				(type default)
			)
			(layer "B.SilkS")
		)
		(fp_line
			(start 0 0.8382)
			(end 0 -0.8382)
			(stroke
				(width 0.1524)
				(type default)
			)
			(layer "B.SilkS")
		)
		(fp_line
			(start 1.651 0.8382)
			(end 1.651 -0.8382)
			(stroke
				(width 0.1524)
				(type default)
			)
			(layer "B.SilkS")
		)
		(fp_line
			(start -1.651 -0.8382)
			(end -1.651 0.8382)
			(stroke
				(width 0.1524)
				(type default)
			)
			(layer "B.SilkS")
		)
		(fp_line
			(start 1.651 -0.8382)
			(end -1.651 -0.8382)
			(stroke
				(width 0.1524)
				(type default)
			)
			(layer "B.SilkS")
		)
		(fp_line
			(start -1.55956 0.7366)
			(end -1.55956 -0.7366)
			(stroke
				(width 0.1)
				(type default)
			)
			(layer "B.Fab")
		)
		(fp_line
			(start -1.524 0.7366)
			(end -1.55956 0.7366)
			(stroke
				(width 0.1)
				(type default)
			)
			(layer "B.Fab")
		)
		(fp_line
			(start 1.524 0.7366)
			(end -1.524 0.7366)
			(stroke
				(width 0.1)
				(type default)
			)
			(layer "B.Fab")
		)
		(fp_line
			(start 1.55956 0.7366)
			(end 1.524 0.7366)
			(stroke
				(width 0.1)
				(type default)
			)
			(layer "B.Fab")
		)
		(fp_line
			(start -1.55956 -0.7366)
			(end -1.524 -0.7366)
			(stroke
				(width 0.1)
				(type default)
			)
			(layer "B.Fab")
		)
		(fp_line
			(start -1.524 -0.7366)
			(end 1.524 -0.7366)
			(stroke
				(width 0.1)
				(type default)
			)
			(layer "B.Fab")
		)
		(fp_line
			(start 1.524 -0.7366)
			(end 1.55956 -0.7366)
			(stroke
				(width 0.1)
				(type default)
			)
			(layer "B.Fab")
		)
		(fp_line
			(start 1.55956 -0.7366)
			(end 1.55956 0.7366)
			(stroke
				(width 0.1)
				(type default)
			)
			(layer "B.Fab")
		)
		(pad "1" smd rect
			(at 0.94996 0 270)
			(size 1.1176 1.3716)
			(layers "B.Cu" "B.Mask" "B.Paste")
			(net "P1V0_AUX")
		)
		(pad "2" smd rect
			(at -0.94996 0 270)
			(size 1.1176 1.3716)
			(layers "B.Cu" "B.Mask" "B.Paste")
			(net "GND")
		)
	)
)
